# S9S_MB_2U (Grand Teton) — schematic netlist excerpt (pin names and nets, part order shuffled) for the footprints in the layout excerpt that follows; sources: Cadence DE-HDL packaged netlist, KiCad conversion of 03242023_DA0F0TMBIJ0_F0T_Motherboard_J_brd_V01_OCP.brd

C416  Q_CAP  22UF 4V 20% X6S  pkg C0402  page 74 : A = PVCCINFAON_CPU0 ; B = GND
R419  Q_RES  33.2 1% CHIP  pkg 0402LF  page 155 : A = RST_OCP_V3_1_BUF_N ; B = RST_PERST0_OCP_SFF_N

(kicad_pcb
	(version 20260206)
	(generator "pcbnew")
	(generator_version "10.0")
	(general
		(thickness 1.6)
		(legacy_teardrops no)
	)
	(paper "A4")
	(title_block
		(title "03242023_DA0F0TMBIJ0_F0T_Motherboard_J_brd_V01_OCP.brd")
		(comment 1 "Grand Teton / footprints 3465-3466 of 6105")
	)
	(layers
		(0 "F.Cu" signal "TOP")
		(4 "In1.Cu" signal "GND")
		(6 "In2.Cu" signal "IN1")
		(8 "In3.Cu" signal "GND1")
		(10 "In4.Cu" signal "IN2")
		(12 "In5.Cu" signal "GND2")
		(14 "In6.Cu" signal "IN3")
		(16 "In7.Cu" signal "GND3")
		(18 "In8.Cu" signal "VCC")
		(20 "In9.Cu" signal "VCC1")
		(22 "In10.Cu" signal "GND4")
		(24 "In11.Cu" signal "IN4")
		(26 "In12.Cu" signal "GND5")
		(28 "In13.Cu" signal "IN5")
		(30 "In14.Cu" signal "GND6")
		(32 "In15.Cu" signal "IN6")
		(34 "In16.Cu" signal "GND7")
		(2 "B.Cu" signal "BOTTOM")
		(9 "F.Adhes" user "F.Adhesive")
		(11 "B.Adhes" user "B.Adhesive")
		(13 "F.Paste" user "Package Geometry/Pastemask Top")
		(15 "B.Paste" user "Package Geometry/Pastemask Bottom")
		(5 "F.SilkS" user "Ref Des/Silkscreen Top")
		(7 "B.SilkS" user "Ref Des/Silkscreen Bottom")
		(1 "F.Mask" user "Board Geometry/Soldermask Top")
		(3 "B.Mask" user "Board Geometry/Soldermask Bottom")
		(17 "Dwgs.User" user "User.Drawings")
		(19 "Cmts.User" user "User.Comments")
		(21 "Eco1.User" user "User.Eco1")
		(23 "Eco2.User" user "User.Eco2")
		(25 "Edge.Cuts" user "Board Geometry/Outline")
		(27 "Margin" user)
		(31 "F.CrtYd" user "Package Geometry/Place Bound Top")
		(29 "B.CrtYd" user "Package Geometry/Place Bound Bottom")
		(35 "F.Fab" user "Ref Des/Assembly Top")
		(33 "B.Fab" user "Ref Des/Assembly Bottom")
	)
	(footprint ""
		(layer "F.Cu")
		(at 365.46663 -238.162338 90)
		(property "Reference" "C416"
			(at 0 0 90)
			(layer "F.SilkS")
			(hide yes)
			(effects
				(font
					(size 1.27 1.27)
				)
			)
		)
		(property "Value" ""
			(at 0 0 90)
			(layer "F.Fab")
			(effects
				(font
					(size 1.27 1.27)
				)
			)
		)
		(duplicate_pad_numbers_are_jumpers no)
		(fp_line
			(start 0.7874 -0.4064)
			(end 0.7874 0.4064)
			(stroke
				(width 0.1524)
				(type default)
			)
			(layer "F.SilkS")
		)
		(fp_line
			(start -0.7874 -0.4064)
			(end 0.7874 -0.4064)
			(stroke
				(width 0.1524)
				(type default)
			)
			(layer "F.SilkS")
		)
		(fp_line
			(start 0.7874 0.4064)
			(end -0.7874 0.4064)
			(stroke
				(width 0.1524)
				(type default)
			)
			(layer "F.SilkS")
		)
		(fp_line
			(start -0.7874 0.4064)
			(end -0.7874 -0.4064)
			(stroke
				(width 0.1524)
				(type default)
			)
			(layer "F.SilkS")
		)
		(fp_line
			(start -0.12065 -0.305054)
			(end -0.12065 -0.2794)
			(stroke
				(width 0.1)
				(type default)
			)
			(layer "F.Fab")
		)
		(fp_line
			(start -0.67945 -0.305054)
			(end -0.12065 -0.305054)
			(stroke
				(width 0.1)
				(type default)
			)
			(layer "F.Fab")
		)
		(fp_line
			(start 0.67945 -0.3048)
			(end 0.67945 0.3048)
			(stroke
				(width 0.1)
				(type default)
			)
			(layer "F.Fab")
		)
		(fp_line
			(start 0.12065 -0.3048)
			(end 0.67945 -0.3048)
			(stroke
				(width 0.1)
				(type default)
			)
			(layer "F.Fab")
		)
		(fp_line
			(start 0.12065 -0.2794)
			(end 0.12065 -0.3048)
			(stroke
				(width 0.1)
				(type default)
			)
			(layer "F.Fab")
		)
		(fp_line
			(start -0.12065 -0.2794)
			(end 0.12065 -0.2794)
			(stroke
				(width 0.1)
				(type default)
			)
			(layer "F.Fab")
		)
		(fp_line
			(start 0.120396 0.2794)
			(end -0.12065 0.2794)
			(stroke
				(width 0.1)
				(type default)
			)
			(layer "F.Fab")
		)
		(fp_line
			(start -0.12065 0.2794)
			(end -0.12065 0.3048)
			(stroke
				(width 0.1)
				(type default)
			)
			(layer "F.Fab")
		)
		(fp_line
			(start 0.67945 0.3048)
			(end 0.120396 0.3048)
			(stroke
				(width 0.1)
				(type default)
			)
			(layer "F.Fab")
		)
		(fp_line
			(start 0.120396 0.3048)
			(end 0.120396 0.2794)
			(stroke
				(width 0.1)
				(type default)
			)
			(layer "F.Fab")
		)
		(fp_line
			(start -0.12065 0.3048)
			(end -0.67945 0.3048)
			(stroke
				(width 0.1)
				(type default)
			)
			(layer "F.Fab")
		)
		(fp_line
			(start -0.67945 0.3048)
			(end -0.67945 -0.305054)
			(stroke
				(width 0.1)
				(type default)
			)
			(layer "F.Fab")
		)
		(pad "1" smd circle
			(at -0.40005 0 90)
			(size 0 0)
			(layers "F.Cu" "F.Mask" "F.Paste")
			(net "PVCCINFAON_CPU0")
		)
		(pad "2" smd circle
			(at 0.40005 0 90)
			(size 0 0)
			(layers "F.Cu" "F.Mask" "F.Paste")
			(net "GND")
		)
	)
	(footprint ""
		(layer "F.Cu")
		(at 436.08625 -16.248126 -90)
		(property "Reference" "R419"
			(at 0 0 270)
			(layer "F.SilkS")
			(hide yes)
			(effects
				(font
					(size 1.27 1.27)
				)
			)
		)
		(property "Value" ""
			(at 0 0 270)
			(layer "F.Fab")
			(effects
				(font
					(size 1.27 1.27)
				)
			)
		)
		(duplicate_pad_numbers_are_jumpers no)
		(fp_line
			(start -0.7874 0.4064)
			(end -0.7874 -0.4064)
			(stroke
				(width 0.1524)
				(type default)
			)
			(layer "F.SilkS")
		)
		(fp_line
			(start 0.7874 0.4064)
			(end -0.7874 0.4064)
			(stroke
				(width 0.1524)
				(type default)
			)
			(layer "F.SilkS")
		)
		(fp_line
			(start -0.7874 -0.4064)
			(end 0.7874 -0.4064)
			(stroke
				(width 0.1524)
				(type default)
			)
			(layer "F.SilkS")
		)
		(fp_line
			(start 0.7874 -0.4064)
			(end 0.7874 0.4064)
			(stroke
				(width 0.1524)
				(type default)
			)
			(layer "F.SilkS")
		)
		(fp_line
			(start -0.67945 0.3048)
			(end -0.67945 -0.305054)
			(stroke
				(width 0.1)
				(type default)
			)
			(layer "F.Fab")
		)
		(fp_line
			(start -0.12065 0.3048)
			(end -0.67945 0.3048)
			(stroke
				(width 0.1)
				(type default)
			)
			(layer "F.Fab")
		)
		(fp_line
			(start 0.120396 0.3048)
			(end 0.120396 0.2794)
			(stroke
				(width 0.1)
				(type default)
			)
			(layer "F.Fab")
		)
		(fp_line
			(start 0.67945 0.3048)
			(end 0.120396 0.3048)
			(stroke
				(width 0.1)
				(type default)
			)
			(layer "F.Fab")
		)
		(fp_line
			(start -0.12065 0.2794)
			(end -0.12065 0.3048)
			(stroke
				(width 0.1)
				(type default)
			)
			(layer "F.Fab")
		)
		(fp_line
			(start 0.120396 0.2794)
			(end -0.12065 0.2794)
			(stroke
				(width 0.1)
				(type default)
			)
			(layer "F.Fab")
		)
		(fp_line
			(start -0.12065 -0.2794)
			(end 0.12065 -0.2794)
			(stroke
				(width 0.1)
				(type default)
			)
			(layer "F.Fab")
		)
		(fp_line
			(start 0.12065 -0.2794)
			(end 0.12065 -0.3048)
			(stroke
				(width 0.1)
				(type default)
			)
			(layer "F.Fab")
		)
		(fp_line
			(start 0.12065 -0.3048)
			(end 0.67945 -0.3048)
			(stroke
				(width 0.1)
				(type default)
			)
			(layer "F.Fab")
		)
		(fp_line
			(start 0.67945 -0.3048)
			(end 0.67945 0.3048)
			(stroke
				(width 0.1)
				(type default)
			)
			(layer "F.Fab")
		)
		(fp_line
			(start -0.67945 -0.305054)
			(end -0.12065 -0.305054)
			(stroke
				(width 0.1)
				(type default)
			)
			(layer "F.Fab")
		)
		(fp_line
			(start -0.12065 -0.305054)
			(end -0.12065 -0.2794)
			(stroke
				(width 0.1)
				(type default)
			)
			(layer "F.Fab")
		)
		(pad "1" smd circle
			(at -0.40005 0 270)
			(size 0 0)
			(layers "F.Cu" "F.Mask" "F.Paste")
			(net "RST_OCP_V3_1_BUF_N")
		)
		(pad "2" smd circle
			(at 0.40005 0 270)
			(size 0 0)
			(layers "F.Cu" "F.Mask" "F.Paste")
			(net "RST_PERST0_OCP_SFF_N")
		)
	)
)
